(kicad_pcb
	(version 20260206)
	(generator "pcbnew")
	(generator_version "10.0")
	(general
		(thickness 1.6)
		(legacy_teardrops no)
	)
	(paper "A4")
	(title_block
		(title "Wiwynn_Tioga_Pass_MB.brd")
		(comment 1 "Tioga Pass / footprints 2602-2608 of 4770")
	)
	(layers
		(0 "F.Cu" signal "TOP")
		(4 "In1.Cu" signal "L2GND")
		(6 "In2.Cu" signal "L3")
		(8 "In3.Cu" signal "L4GND")
		(10 "In4.Cu" signal "L5")
		(12 "In5.Cu" signal "L6GND")
		(14 "In6.Cu" signal "L7VCC")
		(16 "In7.Cu" signal "L8VCC")
		(18 "In8.Cu" signal "L9GND")
		(20 "In9.Cu" signal "L10")
		(22 "In10.Cu" signal "L11GND")
		(24 "In11.Cu" signal "L12")
		(26 "In12.Cu" signal "L13GND")
		(2 "B.Cu" signal "BOTTOM")
		(9 "F.Adhes" user "F.Adhesive")
		(11 "B.Adhes" user "B.Adhesive")
		(13 "F.Paste" user "Package Geometry/Pastemask Top")
		(15 "B.Paste" user "Package Geometry/Pastemask Bottom")
		(5 "F.SilkS" user "Ref Des/Silkscreen Top")
		(7 "B.SilkS" user "Ref Des/Silkscreen Bottom")
		(1 "F.Mask" user "Board Geometry/Soldermask Top")
		(3 "B.Mask" user "Board Geometry/Soldermask Bottom")
		(17 "Dwgs.User" user "User.Drawings")
		(19 "Cmts.User" user "User.Comments")
		(21 "Eco1.User" user "User.Eco1")
		(23 "Eco2.User" user "User.Eco2")
		(25 "Edge.Cuts" user "Board Geometry/Outline")
		(27 "Margin" user)
		(31 "F.CrtYd" user "Package Geometry/Place Bound Top")
		(29 "B.CrtYd" user "Package Geometry/Place Bound Bottom")
		(35 "F.Fab" user "Ref Des/Assembly Top")
		(33 "B.Fab" user "Ref Des/Assembly Bottom")
	)
	(footprint ""
		(layer "B.Cu")
		(at 463.7278 -7.112)
		(property "Reference" "R8E36"
			(at 0 0 0)
			(layer "B.SilkS")
			(hide yes)
			(effects
				(font
					(size 1.27 1.27)
				)
				(justify mirror)
			)
		)
		(property "Value" "*"
			(at -0.064008 -4.108196 0)
			(unlocked yes)
			(layer "B.Fab")
			(hide yes)
			(effects
				(font
					(size 1.27 1.016)
					(thickness 0.1524)
				)
				(justify mirror)
			)
		)
		(property "Device Type" "2K15R2F-1-GP_SMD-RG1-2K15R2F-1A"
			(at -0.064008 -5.632196 0)
			(unlocked yes)
			(layer "B.Fab")
			(hide yes)
			(effects
				(font
					(size 1.27 1.016)
					(thickness 0.1524)
				)
				(justify mirror)
			)
		)
		(duplicate_pad_numbers_are_jumpers no)
		(fp_line
			(start -0.508 -0.9398)
			(end 0.508 -0.9398)
			(stroke
				(width 0.1524)
				(type default)
			)
			(layer "B.SilkS")
		)
		(fp_line
			(start 0.508 -0.9398)
			(end 0.508 0.9398)
			(stroke
				(width 0.1524)
				(type default)
			)
			(layer "B.SilkS")
		)
		(fp_rect
			(start 0.508 0.9398)
			(end -0.508 -0.9398)
			(stroke
				(width 0)
				(type default)
			)
			(fill no)
			(layer "B.CrtYd")
		)
		(fp_rect
			(start 0.508 0.9398)
			(end -0.508 -0.9398)
			(stroke
				(width 0)
				(type default)
			)
			(fill no)
			(layer "B.Fab")
		)
		(pad "1" smd custom
			(at 0 -0.4445 180)
			(size 0.1397 0.1397)
			(layers "B.Cu" "B.Mask" "B.Paste")
			(net "P3V3_STBY")
			(options
				(clearance outline)
				(anchor circle)
			)
			(primitives
				(gr_poly
					(pts
						(arc
							(start -0.1778 0.2794)
							(mid -0.249642 0.249642)
							(end -0.2794 0.1778)
						)
						(arc
							(start -0.2794 -0.1778)
							(mid -0.249642 -0.249642)
							(end -0.1778 -0.2794)
						)
						(arc
							(start 0.1778 -0.2794)
							(mid 0.249642 -0.249642)
							(end 0.2794 -0.1778)
						)
						(arc
							(start 0.2794 0.1778)
							(mid 0.249642 0.249642)
							(end 0.1778 0.2794)
						)
					)
					(width 0)
					(fill yes)
				)
			)
		)
		(pad "2" smd custom
			(at 0 0.4445 180)
			(size 0.1397 0.1397)
			(layers "B.Cu" "B.Mask" "B.Paste")
			(net "FM_PE_SLOTX24_WAKE_N")
			(options
				(clearance outline)
				(anchor circle)
			)
			(primitives
				(gr_poly
					(pts
						(arc
							(start -0.1778 0.2794)
							(mid -0.249642 0.249642)
							(end -0.2794 0.1778)
						)
						(arc
							(start -0.2794 -0.1778)
							(mid -0.249642 -0.249642)
							(end -0.1778 -0.2794)
						)
						(arc
							(start 0.1778 -0.2794)
							(mid 0.249642 -0.249642)
							(end 0.2794 -0.1778)
						)
						(arc
							(start 0.2794 0.1778)
							(mid 0.249642 0.249642)
							(end 0.1778 0.2794)
						)
					)
					(width 0)
					(fill yes)
				)
			)
		)
	)
	(footprint ""
		(layer "B.Cu")
		(at 94.663768 -8.122412 90)
		(property "Reference" "C8U8"
			(at 0 0 90)
			(layer "B.SilkS")
			(hide yes)
			(effects
				(font
					(size 1.27 1.27)
				)
				(justify mirror)
			)
		)
		(property "Value" ""
			(at 0 0 90)
			(layer "B.Fab")
			(effects
				(font
					(size 1.27 1.27)
				)
				(justify mirror)
			)
		)
		(duplicate_pad_numbers_are_jumpers no)
		(fp_poly
			(pts
				(xy 0.7239 -0.2159) (xy -0.7239 -0.2159) (xy -0.7239 1.9939) (xy 0.7239 1.9939)
			)
			(stroke
				(width 0)
				(type default)
			)
			(fill no)
			(layer "B.CrtYd")
		)
		(fp_line
			(start 0.7239 -0.2159)
			(end 0.7239 1.9939)
			(stroke
				(width 0.1)
				(type default)
			)
			(layer "B.Fab")
		)
		(fp_line
			(start -0.7239 -0.2159)
			(end 0.7239 -0.2159)
			(stroke
				(width 0.1)
				(type default)
			)
			(layer "B.Fab")
		)
		(fp_line
			(start 0.7239 1.9939)
			(end -0.7239 1.9939)
			(stroke
				(width 0.1)
				(type default)
			)
			(layer "B.Fab")
		)
		(fp_line
			(start -0.7239 1.9939)
			(end -0.7239 -0.2159)
			(stroke
				(width 0.1)
				(type default)
			)
			(layer "B.Fab")
		)
		(pad "1" smd rect
			(at 0 0 270)
			(size 1.27 1.016)
			(layers "B.Cu" "B.Mask" "B.Paste")
			(net "PVDDQ_GHJ")
		)
		(pad "2" smd rect
			(at 0 1.778 270)
			(size 1.27 1.016)
			(layers "B.Cu" "B.Mask" "B.Paste")
			(net "GND")
		)
		(zone
			(layer "B.Cu")
			(hatch none 0.5)
			(connect_pads
				(clearance 0)
			)
			(min_thickness 0.25)
			(keepout
				(tracks not_allowed)
				(vias allowed)
				(pads allowed)
				(copperpour not_allowed)
				(footprints allowed)
			)
			(placement
				(enabled no)
				(sheetname "")
			)
			(fill
				(thermal_gap 0.5)
				(thermal_bridge_width 0.5)
				(island_removal_mode 0)
			)
			(polygon
				(pts
					(xy 95.171768 -8.757412) (xy 95.171768 -7.487412) (xy 95.933768 -7.487412) (xy 95.933768 -8.757412)
				)
			)
		)
	)
	(footprint ""
		(layer "B.Cu")
		(at 385.217924 -23.869904 90)
		(property "Reference" "C2T23"
			(at 0 0 90)
			(layer "B.SilkS")
			(hide yes)
			(effects
				(font
					(size 1.27 1.27)
				)
				(justify mirror)
			)
		)
		(property "Value" ""
			(at 0 0 90)
			(layer "B.Fab")
			(effects
				(font
					(size 1.27 1.27)
				)
				(justify mirror)
			)
		)
		(duplicate_pad_numbers_are_jumpers no)
		(fp_poly
			(pts
				(xy -0.3048 -0.1016) (xy -0.3048 0.9906) (xy 0.3048 0.9906) (xy 0.3048 -0.1016)
			)
			(stroke
				(width 0)
				(type default)
			)
			(fill no)
			(layer "B.CrtYd")
		)
		(fp_line
			(start 0.3048 -0.1016)
			(end 0.3048 0.9906)
			(stroke
				(width 0.1)
				(type default)
			)
			(layer "B.Fab")
		)
		(fp_line
			(start -0.3048 -0.1016)
			(end 0.3048 -0.1016)
			(stroke
				(width 0.1)
				(type default)
			)
			(layer "B.Fab")
		)
		(fp_line
			(start 0.3048 0.9906)
			(end -0.3048 0.9906)
			(stroke
				(width 0.1)
				(type default)
			)
			(layer "B.Fab")
		)
		(fp_line
			(start -0.3048 0.9906)
			(end -0.3048 -0.1016)
			(stroke
				(width 0.1)
				(type default)
			)
			(layer "B.Fab")
		)
		(pad "1" smd rect
			(at 0 0 270)
			(size 0.508 0.508)
			(layers "B.Cu" "B.Mask" "B.Paste")
			(net "P3E_PCH_M2_TX_C_DN<3>")
		)
		(pad "2" smd rect
			(at 0 0.889 270)
			(size 0.508 0.508)
			(layers "B.Cu" "B.Mask" "B.Paste")
			(net "P3E_PCH_M2_TX_DN<3>")
		)
		(zone
			(layer "B.Cu")
			(hatch none 0.5)
			(connect_pads
				(clearance 0)
			)
			(min_thickness 0.25)
			(keepout
				(tracks allowed)
				(vias not_allowed)
				(pads allowed)
				(copperpour not_allowed)
				(footprints allowed)
			)
			(placement
				(enabled no)
				(sheetname "")
			)
			(fill
				(thermal_gap 0.5)
				(thermal_bridge_width 0.5)
				(island_removal_mode 0)
			)
			(polygon
				(pts
					(xy 385.471924 -24.123904) (xy 385.471924 -23.615904) (xy 385.852924 -23.615904) (xy 385.852924 -24.123904)
				)
			)
		)
		(zone
			(layer "B.Cu")
			(hatch none 0.5)
			(connect_pads
				(clearance 0)
			)
			(min_thickness 0.25)
			(keepout
				(tracks not_allowed)
				(vias allowed)
				(pads allowed)
				(copperpour not_allowed)
				(footprints allowed)
			)
			(placement
				(enabled no)
				(sheetname "")
			)
			(fill
				(thermal_gap 0.5)
				(thermal_bridge_width 0.5)
				(island_removal_mode 0)
			)
			(polygon
				(pts
					(xy 385.852924 -24.123904) (xy 385.852924 -23.615904) (xy 385.471924 -23.615904) (xy 385.471924 -24.123904)
				)
			)
		)
	)
	(footprint ""
		(layer "B.Cu")
		(at 273.052286 -85.06714)
		(property "Reference" "C5P4"
			(at 0 0 0)
			(layer "B.SilkS")
			(hide yes)
			(effects
				(font
					(size 1.27 1.27)
				)
				(justify mirror)
			)
		)
		(property "Value" ""
			(at 0 0 0)
			(layer "B.Fab")
			(effects
				(font
					(size 1.27 1.27)
				)
				(justify mirror)
			)
		)
		(duplicate_pad_numbers_are_jumpers no)
		(fp_poly
			(pts
				(xy 0.7239 -0.2159) (xy -0.7239 -0.2159) (xy -0.7239 1.9939) (xy 0.7239 1.9939)
			)
			(stroke
				(width 0)
				(type default)
			)
			(fill no)
			(layer "B.CrtYd")
		)
		(fp_line
			(start -0.7239 -0.2159)
			(end 0.7239 -0.2159)
			(stroke
				(width 0.1)
				(type default)
			)
			(layer "B.Fab")
		)
		(fp_line
			(start -0.7239 1.9939)
			(end -0.7239 -0.2159)
			(stroke
				(width 0.1)
				(type default)
			)
			(layer "B.Fab")
		)
		(fp_line
			(start 0.7239 -0.2159)
			(end 0.7239 1.9939)
			(stroke
				(width 0.1)
				(type default)
			)
			(layer "B.Fab")
		)
		(fp_line
			(start 0.7239 1.9939)
			(end -0.7239 1.9939)
			(stroke
				(width 0.1)
				(type default)
			)
			(layer "B.Fab")
		)
		(pad "1" smd rect
			(at 0 0 180)
			(size 1.27 1.016)
			(layers "B.Cu" "B.Mask" "B.Paste")
			(net "PVDDQ_DEF")
		)
		(pad "2" smd rect
			(at 0 1.778 180)
			(size 1.27 1.016)
			(layers "B.Cu" "B.Mask" "B.Paste")
			(net "GND")
		)
		(zone
			(layer "B.Cu")
			(hatch none 0.5)
			(connect_pads
				(clearance 0)
			)
			(min_thickness 0.25)
			(keepout
				(tracks not_allowed)
				(vias allowed)
				(pads allowed)
				(copperpour not_allowed)
				(footprints allowed)
			)
			(placement
				(enabled no)
				(sheetname "")
			)
			(fill
				(thermal_gap 0.5)
				(thermal_bridge_width 0.5)
				(island_removal_mode 0)
			)
			(polygon
				(pts
					(xy 273.687286 -84.55914) (xy 272.417286 -84.55914) (xy 272.417286 -83.79714) (xy 273.687286 -83.79714)
				)
			)
		)
	)
	(footprint ""
		(layer "B.Cu")
		(at 192.913 -134.874 180)
		(property "Reference" "R6M2"
			(at 0 0 0)
			(layer "B.SilkS")
			(hide yes)
			(effects
				(font
					(size 1.27 1.27)
				)
				(justify mirror)
			)
		)
		(property "Value" ""
			(at 0 0 0)
			(layer "B.Fab")
			(effects
				(font
					(size 1.27 1.27)
				)
				(justify mirror)
			)
		)
		(duplicate_pad_numbers_are_jumpers no)
		(fp_poly
			(pts
				(xy 0.2794 -0.1016) (xy -0.2794 -0.1016) (xy -0.2794 0.9906) (xy 0.2794 0.9906)
			)
			(stroke
				(width 0)
				(type default)
			)
			(fill no)
			(layer "B.CrtYd")
		)
		(fp_line
			(start 0.2794 0.9906)
			(end -0.2794 0.9906)
			(stroke
				(width 0.1)
				(type default)
			)
			(layer "B.Fab")
		)
		(fp_line
			(start 0.2794 -0.1016)
			(end 0.2794 0.9906)
			(stroke
				(width 0.1)
				(type default)
			)
			(layer "B.Fab")
		)
		(fp_line
			(start -0.2794 0.9906)
			(end -0.2794 -0.1016)
			(stroke
				(width 0.1)
				(type default)
			)
			(layer "B.Fab")
		)
		(fp_line
			(start -0.2794 -0.1016)
			(end 0.2794 -0.1016)
			(stroke
				(width 0.1)
				(type default)
			)
			(layer "B.Fab")
		)
		(pad "1" smd rect
			(at 0 0)
			(size 0.508 0.508)
			(layers "B.Cu" "B.Mask" "B.Paste")
			(net "M_D_CPU_VREF")
		)
		(pad "2" smd rect
			(at 0 0.889)
			(size 0.508 0.508)
			(layers "B.Cu" "B.Mask" "B.Paste")
			(net "M_D_VREF")
		)
		(zone
			(layer "B.Cu")
			(hatch none 0.5)
			(connect_pads
				(clearance 0)
			)
			(min_thickness 0.25)
			(keepout
				(tracks not_allowed)
				(vias allowed)
				(pads allowed)
				(copperpour not_allowed)
				(footprints allowed)
			)
			(placement
				(enabled no)
				(sheetname "")
			)
			(fill
				(thermal_gap 0.5)
				(thermal_bridge_width 0.5)
				(island_removal_mode 0)
			)
			(polygon
				(pts
					(xy 192.659 -135.509) (xy 193.167 -135.509) (xy 193.167 -135.128) (xy 192.659 -135.128)
				)
			)
		)
		(zone
			(layer "B.Cu")
			(hatch none 0.5)
			(connect_pads
				(clearance 0)
			)
			(min_thickness 0.25)
			(keepout
				(tracks allowed)
				(vias not_allowed)
				(pads allowed)
				(copperpour not_allowed)
				(footprints allowed)
			)
			(placement
				(enabled no)
				(sheetname "")
			)
			(fill
				(thermal_gap 0.5)
				(thermal_bridge_width 0.5)
				(island_removal_mode 0)
			)
			(polygon
				(pts
					(xy 192.659 -135.128) (xy 193.167 -135.128) (xy 193.167 -135.509) (xy 192.659 -135.509)
				)
			)
		)
	)
	(footprint ""
		(layer "B.Cu")
		(at 162.7886 -80.3402 90)
		(property "Reference" "R7P6"
			(at 0 0 90)
			(layer "B.SilkS")
			(hide yes)
			(effects
				(font
					(size 1.27 1.27)
				)
				(justify mirror)
			)
		)
		(property "Value" ""
			(at 0 0 90)
			(layer "B.Fab")
			(effects
				(font
					(size 1.27 1.27)
				)
				(justify mirror)
			)
		)
		(duplicate_pad_numbers_are_jumpers no)
		(fp_poly
			(pts
				(xy 0.2794 -0.1016) (xy -0.2794 -0.1016) (xy -0.2794 0.9906) (xy 0.2794 0.9906)
			)
			(stroke
				(width 0)
				(type default)
			)
			(fill no)
			(layer "B.CrtYd")
		)
		(fp_line
			(start 0.2794 -0.1016)
			(end 0.2794 0.9906)
			(stroke
				(width 0.1)
				(type default)
			)
			(layer "B.Fab")
		)
		(fp_line
			(start -0.2794 -0.1016)
			(end 0.2794 -0.1016)
			(stroke
				(width 0.1)
				(type default)
			)
			(layer "B.Fab")
		)
		(fp_line
			(start 0.2794 0.9906)
			(end -0.2794 0.9906)
			(stroke
				(width 0.1)
				(type default)
			)
			(layer "B.Fab")
		)
		(fp_line
			(start -0.2794 0.9906)
			(end -0.2794 -0.1016)
			(stroke
				(width 0.1)
				(type default)
			)
			(layer "B.Fab")
		)
		(pad "1" smd rect
			(at 0 0 270)
			(size 0.508 0.508)
			(layers "B.Cu" "B.Mask" "B.Paste")
			(net "CLK_100M_CPU1_RC_REFCLK0_DP")
		)
		(pad "2" smd rect
			(at 0 0.889 270)
			(size 0.508 0.508)
			(layers "B.Cu" "B.Mask" "B.Paste")
			(net "GND")
		)
		(zone
			(layer "B.Cu")
			(hatch none 0.5)
			(connect_pads
				(clearance 0)
			)
			(min_thickness 0.25)
			(keepout
				(tracks allowed)
				(vias not_allowed)
				(pads allowed)
				(copperpour not_allowed)
				(footprints allowed)
			)
			(placement
				(enabled no)
				(sheetname "")
			)
			(fill
				(thermal_gap 0.5)
				(thermal_bridge_width 0.5)
				(island_removal_mode 0)
			)
			(polygon
				(pts
					(xy 163.0426 -80.5942) (xy 163.0426 -80.0862) (xy 163.4236 -80.0862) (xy 163.4236 -80.5942)
				)
			)
		)
		(zone
			(layer "B.Cu")
			(hatch none 0.5)
			(connect_pads
				(clearance 0)
			)
			(min_thickness 0.25)
			(keepout
				(tracks not_allowed)
				(vias allowed)
				(pads allowed)
				(copperpour not_allowed)
				(footprints allowed)
			)
			(placement
				(enabled no)
				(sheetname "")
			)
			(fill
				(thermal_gap 0.5)
				(thermal_bridge_width 0.5)
				(island_removal_mode 0)
			)
			(polygon
				(pts
					(xy 163.4236 -80.5942) (xy 163.4236 -80.0862) (xy 163.0426 -80.0862) (xy 163.0426 -80.5942)
				)
			)
		)
	)
	(footprint ""
		(layer "B.Cu")
		(at 112.217454 -79.575914 180)
		(property "Reference" "C7P5"
			(at 0 0 0)
			(layer "B.SilkS")
			(hide yes)
			(effects
				(font
					(size 1.27 1.27)
				)
				(justify mirror)
			)
		)
		(property "Value" ""
			(at 0 0 0)
			(layer "B.Fab")
			(effects
				(font
					(size 1.27 1.27)
				)
				(justify mirror)
			)
		)
		(duplicate_pad_numbers_are_jumpers no)
		(fp_poly
			(pts
				(xy 0.7239 -0.2159) (xy -0.7239 -0.2159) (xy -0.7239 1.9939) (xy 0.7239 1.9939)
			)
			(stroke
				(width 0)
				(type default)
			)
			(fill no)
			(layer "B.CrtYd")
		)
		(fp_line
			(start 0.7239 1.9939)
			(end -0.7239 1.9939)
			(stroke
				(width 0.1)
				(type default)
			)
			(layer "B.Fab")
		)
		(fp_line
			(start 0.7239 -0.2159)
			(end 0.7239 1.9939)
			(stroke
				(width 0.1)
				(type default)
			)
			(layer "B.Fab")
		)
		(fp_line
			(start -0.7239 1.9939)
			(end -0.7239 -0.2159)
			(stroke
				(width 0.1)
				(type default)
			)
			(layer "B.Fab")
		)
		(fp_line
			(start -0.7239 -0.2159)
			(end 0.7239 -0.2159)
			(stroke
				(width 0.1)
				(type default)
			)
			(layer "B.Fab")
		)
		(pad "1" smd rect
			(at 0 0)
			(size 1.27 1.016)
			(layers "B.Cu" "B.Mask" "B.Paste")
			(net "PVCCMCP_CPU1")
		)
		(pad "2" smd rect
			(at 0 1.778)
			(size 1.27 1.016)
			(layers "B.Cu" "B.Mask" "B.Paste")
			(net "GND")
		)
		(zone
			(layer "B.Cu")
			(hatch none 0.5)
			(connect_pads
				(clearance 0)
			)
			(min_thickness 0.25)
			(keepout
				(tracks not_allowed)
				(vias allowed)
				(pads allowed)
				(copperpour not_allowed)
				(footprints allowed)
			)
			(placement
				(enabled no)
				(sheetname "")
			)
			(fill
				(thermal_gap 0.5)
				(thermal_bridge_width 0.5)
				(island_removal_mode 0)
			)
			(polygon
				(pts
					(xy 111.582454 -80.083914) (xy 112.852454 -80.083914) (xy 112.852454 -80.845914) (xy 111.582454 -80.845914)
				)
			)
		)
	)
)
